(kicad_pcb
	(version 20260206)
	(generator "pcbnew")
	(generator_version "10.0")
	(general
		(thickness 1.6)
		(legacy_teardrops no)
	)
	(paper "A4")
	(title_block
		(title "panther-plus-userver — 13130-1b_20150205.brd")
		(comment 1 "Honey Badger (Wiwynn) / footprints 417-425 of 1509")
	)
	(layers
		(0 "F.Cu" signal "TOP")
		(4 "In1.Cu" signal "L2")
		(6 "In2.Cu" signal "L3")
		(8 "In3.Cu" signal "L4")
		(10 "In4.Cu" signal "L5")
		(12 "In5.Cu" signal "L6")
		(14 "In6.Cu" signal "L7")
		(16 "In7.Cu" signal "L8")
		(18 "In8.Cu" signal "L9")
		(20 "In9.Cu" signal "L10")
		(22 "In10.Cu" signal "L11")
		(2 "B.Cu" signal "BOTTOM")
		(9 "F.Adhes" user "F.Adhesive")
		(11 "B.Adhes" user "B.Adhesive")
		(13 "F.Paste" user "Package Geometry/Pastemask Top")
		(15 "B.Paste" user "Package Geometry/Pastemask Bottom")
		(5 "F.SilkS" user "Ref Des/Silkscreen Top")
		(7 "B.SilkS" user "Ref Des/Silkscreen Bottom")
		(1 "F.Mask" user "Board Geometry/Soldermask Top")
		(3 "B.Mask" user "Board Geometry/Soldermask Bottom")
		(17 "Dwgs.User" user "User.Drawings")
		(19 "Cmts.User" user "User.Comments")
		(21 "Eco1.User" user "User.Eco1")
		(23 "Eco2.User" user "User.Eco2")
		(25 "Edge.Cuts" user "Board Geometry/Outline")
		(27 "Margin" user)
		(31 "F.CrtYd" user "Package Geometry/Place Bound Top")
		(29 "B.CrtYd" user "Package Geometry/Place Bound Bottom")
		(35 "F.Fab" user "Ref Des/Assembly Top")
		(33 "B.Fab" user "Ref Des/Assembly Bottom")
	)
	(footprint ""
		(layer "F.Cu")
		(at 140.081 -47.625 180)
		(property "Reference" "TP37"
			(at 0 0 180)
			(layer "F.SilkS")
			(hide yes)
			(effects
				(font
					(size 1.27 1.27)
				)
			)
		)
		(property "Value" "TPAD32-GP"
			(at 0 -3.166364 180)
			(unlocked yes)
			(layer "F.Fab")
			(hide yes)
			(effects
				(font
					(size 1.016 1.016)
					(thickness 0.1524)
				)
			)
		)
		(property "Device Type" "TPAD32"
			(at 0 -4.690618 180)
			(unlocked yes)
			(layer "F.Fab")
			(hide yes)
			(effects
				(font
					(size 1.016 1.016)
					(thickness 0.1524)
				)
			)
		)
		(duplicate_pad_numbers_are_jumpers no)
		(fp_poly
			(pts
				(arc
					(start -0.7112 0)
					(mid 0.7112 0)
					(end -0.7112 0)
				)
			)
			(stroke
				(width 0)
				(type default)
			)
			(fill no)
			(layer "F.CrtYd")
		)
		(fp_poly
			(pts
				(arc
					(start -0.7112 0)
					(mid 0.7112 0)
					(end -0.7112 0)
				)
			)
			(stroke
				(width 0)
				(type default)
			)
			(fill no)
			(layer "F.Fab")
		)
		(pad "1" smd circle
			(at 0 0 180)
			(size 0.8128 0.8128)
			(layers "F.Cu" "F.Mask" "F.Paste")
			(net "C_NCE#")
		)
	)
	(footprint ""
		(layer "F.Cu")
		(at 26.7462 -60.833 -90)
		(property "Reference" "PR38"
			(at 0 0 270)
			(layer "F.SilkS")
			(hide yes)
			(effects
				(font
					(size 1.27 1.27)
				)
			)
		)
		(property "Value" "0R2J-2-GP"
			(at 1.7907 -1.1176 270)
			(unlocked yes)
			(layer "F.Fab")
			(hide yes)
			(effects
				(font
					(size 1.016 1.016)
					(thickness 0.1524)
				)
			)
		)
		(property "Device Type" "R402H16"
			(at 1.7907 -2.6416 270)
			(unlocked yes)
			(layer "F.Fab")
			(hide yes)
			(effects
				(font
					(size 1.016 1.016)
					(thickness 0.1524)
				)
			)
		)
		(duplicate_pad_numbers_are_jumpers no)
		(fp_rect
			(start -0.381 0.8382)
			(end 0.381 -0.8382)
			(stroke
				(width 0)
				(type default)
			)
			(fill no)
			(layer "F.CrtYd")
		)
		(fp_rect
			(start -0.381 0.8382)
			(end 0.381 -0.8382)
			(stroke
				(width 0)
				(type default)
			)
			(fill no)
			(layer "F.Fab")
		)
		(pad "1" smd custom
			(at 0 -0.4318 270)
			(size 0.127 0.127)
			(layers "F.Cu" "F.Mask" "F.Paste")
			(net "VCCP_5VBIAS")
			(options
				(clearance outline)
				(anchor circle)
			)
			(primitives
				(gr_poly
					(pts
						(arc
							(start -0.2032 -0.2794)
							(mid -0.239121 -0.264521)
							(end -0.254 -0.2286)
						)
						(arc
							(start -0.254 0.2286)
							(mid -0.239121 0.264521)
							(end -0.2032 0.2794)
						)
						(arc
							(start 0.2032 0.2794)
							(mid 0.239121 0.264521)
							(end 0.254 0.2286)
						)
						(arc
							(start 0.254 -0.2286)
							(mid 0.239121 -0.264521)
							(end 0.2032 -0.2794)
						)
					)
					(width 0)
					(fill yes)
				)
			)
		)
		(pad "2" smd custom
			(at 0 0.4318 270)
			(size 0.127 0.127)
			(layers "F.Cu" "F.Mask" "F.Paste")
			(net "VR_PVCCP_PVNN_VCCP")
			(options
				(clearance outline)
				(anchor circle)
			)
			(primitives
				(gr_poly
					(pts
						(arc
							(start -0.2032 -0.2794)
							(mid -0.239121 -0.264521)
							(end -0.254 -0.2286)
						)
						(arc
							(start -0.254 0.2286)
							(mid -0.239121 0.264521)
							(end -0.2032 0.2794)
						)
						(arc
							(start 0.2032 0.2794)
							(mid 0.239121 0.264521)
							(end 0.254 0.2286)
						)
						(arc
							(start 0.254 -0.2286)
							(mid 0.239121 -0.264521)
							(end 0.2032 -0.2794)
						)
					)
					(width 0)
					(fill yes)
				)
			)
		)
	)
	(footprint ""
		(layer "F.Cu")
		(at 63.119 -29.972 180)
		(property "Reference" "C113"
			(at 0 0 180)
			(layer "F.SilkS")
			(hide yes)
			(effects
				(font
					(size 1.27 1.27)
				)
			)
		)
		(property "Value" "SCD47U25V2KX-GP"
			(at 1.8923 -1.2065 180)
			(unlocked yes)
			(layer "F.Fab")
			(hide yes)
			(effects
				(font
					(size 1.016 1.016)
					(thickness 0.1524)
				)
			)
		)
		(property "Device Type" "C402H24"
			(at 1.8923 -2.7305 180)
			(unlocked yes)
			(layer "F.Fab")
			(hide yes)
			(effects
				(font
					(size 1.016 1.016)
					(thickness 0.1524)
				)
			)
		)
		(duplicate_pad_numbers_are_jumpers no)
		(fp_rect
			(start -0.381 0.7366)
			(end 0.381 -0.7366)
			(stroke
				(width 0)
				(type default)
			)
			(fill no)
			(layer "F.CrtYd")
		)
		(fp_rect
			(start -0.381 0.7366)
			(end 0.381 -0.7366)
			(stroke
				(width 0)
				(type default)
			)
			(fill no)
			(layer "F.Fab")
		)
		(pad "1" smd custom
			(at 0 -0.4572 180)
			(size 0.1143 0.1143)
			(layers "F.Cu" "F.Mask" "F.Paste")
			(net "SW_P1V8_EN_LV")
			(options
				(clearance outline)
				(anchor circle)
			)
			(primitives
				(gr_poly
					(pts
						(arc
							(start -0.254 -0.1778)
							(mid -0.239121 -0.213721)
							(end -0.2032 -0.2286)
						)
						(arc
							(start 0.2032 -0.2286)
							(mid 0.239121 -0.213721)
							(end 0.254 -0.1778)
						)
						(arc
							(start 0.254 0.1778)
							(mid 0.239121 0.213721)
							(end 0.2032 0.2286)
						)
						(arc
							(start -0.2032 0.2286)
							(mid -0.239121 0.213721)
							(end -0.254 0.1778)
						)
					)
					(width 0)
					(fill yes)
				)
			)
		)
		(pad "2" smd custom
			(at 0 0.4572 180)
			(size 0.1143 0.1143)
			(layers "F.Cu" "F.Mask" "F.Paste")
			(net "P1V8")
			(options
				(clearance outline)
				(anchor circle)
			)
			(primitives
				(gr_poly
					(pts
						(arc
							(start -0.254 -0.1778)
							(mid -0.239121 -0.213721)
							(end -0.2032 -0.2286)
						)
						(arc
							(start 0.2032 -0.2286)
							(mid 0.239121 -0.213721)
							(end 0.254 -0.1778)
						)
						(arc
							(start 0.254 0.1778)
							(mid 0.239121 0.213721)
							(end 0.2032 0.2286)
						)
						(arc
							(start -0.2032 0.2286)
							(mid -0.239121 0.213721)
							(end -0.254 0.1778)
						)
					)
					(width 0)
					(fill yes)
				)
			)
		)
	)
	(footprint ""
		(layer "F.Cu")
		(at 197.993 -37.338 180)
		(property "Reference" "PR91"
			(at 0 0 180)
			(layer "F.SilkS")
			(hide yes)
			(effects
				(font
					(size 1.27 1.27)
				)
			)
		)
		(property "Value" "10KR2F-2-GP"
			(at 1.7907 -1.1176 180)
			(unlocked yes)
			(layer "F.Fab")
			(hide yes)
			(effects
				(font
					(size 1.016 1.016)
					(thickness 0.1524)
				)
			)
		)
		(property "Device Type" "R402H16"
			(at 1.7907 -2.6416 180)
			(unlocked yes)
			(layer "F.Fab")
			(hide yes)
			(effects
				(font
					(size 1.016 1.016)
					(thickness 0.1524)
				)
			)
		)
		(duplicate_pad_numbers_are_jumpers no)
		(fp_rect
			(start -0.381 0.8382)
			(end 0.381 -0.8382)
			(stroke
				(width 0)
				(type default)
			)
			(fill no)
			(layer "F.CrtYd")
		)
		(fp_rect
			(start -0.381 0.8382)
			(end 0.381 -0.8382)
			(stroke
				(width 0)
				(type default)
			)
			(fill no)
			(layer "F.Fab")
		)
		(pad "1" smd custom
			(at 0 -0.4318 180)
			(size 0.127 0.127)
			(layers "F.Cu" "F.Mask" "F.Paste")
			(net "GND")
			(options
				(clearance outline)
				(anchor circle)
			)
			(primitives
				(gr_poly
					(pts
						(arc
							(start -0.2032 -0.2794)
							(mid -0.239121 -0.264521)
							(end -0.254 -0.2286)
						)
						(arc
							(start -0.254 0.2286)
							(mid -0.239121 0.264521)
							(end -0.2032 0.2794)
						)
						(arc
							(start 0.2032 0.2794)
							(mid 0.239121 0.264521)
							(end 0.254 0.2286)
						)
						(arc
							(start 0.254 -0.2286)
							(mid 0.239121 -0.264521)
							(end 0.2032 -0.2794)
						)
					)
					(width 0)
					(fill yes)
				)
			)
		)
		(pad "2" smd custom
			(at 0 0.4318 180)
			(size 0.127 0.127)
			(layers "F.Cu" "F.Mask" "F.Paste")
			(net "VR_PVDDR_A_GL1_BG")
			(options
				(clearance outline)
				(anchor circle)
			)
			(primitives
				(gr_poly
					(pts
						(arc
							(start -0.2032 -0.2794)
							(mid -0.239121 -0.264521)
							(end -0.254 -0.2286)
						)
						(arc
							(start -0.254 0.2286)
							(mid -0.239121 0.264521)
							(end -0.2032 0.2794)
						)
						(arc
							(start 0.2032 0.2794)
							(mid 0.239121 0.264521)
							(end 0.254 0.2286)
						)
						(arc
							(start 0.254 -0.2286)
							(mid 0.239121 -0.264521)
							(end 0.2032 -0.2794)
						)
					)
					(width 0)
					(fill yes)
				)
			)
		)
	)
	(footprint ""
		(layer "F.Cu")
		(at 184.912 -22.8854)
		(property "Reference" "PR165"
			(at 0 0 0)
			(layer "F.SilkS")
			(hide yes)
			(effects
				(font
					(size 1.27 1.27)
				)
			)
		)
		(property "Value" "0R2J-2-GP"
			(at 0.064008 -3.993896 0)
			(unlocked yes)
			(layer "F.Fab")
			(hide yes)
			(effects
				(font
					(size 1.016 1.016)
					(thickness 0.1524)
				)
			)
		)
		(property "Device Type" "R402H16"
			(at 0.064008 -5.517896 0)
			(unlocked yes)
			(layer "F.Fab")
			(hide yes)
			(effects
				(font
					(size 1.016 1.016)
					(thickness 0.1524)
				)
			)
		)
		(duplicate_pad_numbers_are_jumpers no)
		(fp_rect
			(start -0.381 0.8382)
			(end 0.381 -0.8382)
			(stroke
				(width 0)
				(type default)
			)
			(fill no)
			(layer "F.CrtYd")
		)
		(fp_rect
			(start -0.381 0.8382)
			(end 0.381 -0.8382)
			(stroke
				(width 0)
				(type default)
			)
			(fill no)
			(layer "F.Fab")
		)
		(pad "1" smd custom
			(at 0 -0.4318)
			(size 0.127 0.127)
			(layers "F.Cu" "F.Mask" "F.Paste")
			(net "PWRGD_PVTT_PG")
			(options
				(clearance outline)
				(anchor circle)
			)
			(primitives
				(gr_poly
					(pts
						(arc
							(start -0.2032 -0.2794)
							(mid -0.239121 -0.264521)
							(end -0.254 -0.2286)
						)
						(arc
							(start -0.254 0.2286)
							(mid -0.239121 0.264521)
							(end -0.2032 0.2794)
						)
						(arc
							(start 0.2032 0.2794)
							(mid 0.239121 0.264521)
							(end 0.254 0.2286)
						)
						(arc
							(start 0.254 -0.2286)
							(mid 0.239121 -0.264521)
							(end 0.2032 -0.2794)
						)
					)
					(width 0)
					(fill yes)
				)
			)
		)
		(pad "2" smd custom
			(at 0 0.4318)
			(size 0.127 0.127)
			(layers "F.Cu" "F.Mask" "F.Paste")
			(net "PV_VTT_DDR_B_R_PG")
			(options
				(clearance outline)
				(anchor circle)
			)
			(primitives
				(gr_poly
					(pts
						(arc
							(start -0.2032 -0.2794)
							(mid -0.239121 -0.264521)
							(end -0.254 -0.2286)
						)
						(arc
							(start -0.254 0.2286)
							(mid -0.239121 0.264521)
							(end -0.2032 0.2794)
						)
						(arc
							(start 0.2032 0.2794)
							(mid 0.239121 0.264521)
							(end 0.254 0.2286)
						)
						(arc
							(start 0.254 -0.2286)
							(mid 0.239121 -0.264521)
							(end 0.2032 -0.2794)
						)
					)
					(width 0)
					(fill yes)
				)
			)
		)
	)
	(footprint ""
		(layer "F.Cu")
		(at 175.7426 -46.5074)
		(property "Reference" "R184"
			(at 0 0 0)
			(layer "F.SilkS")
			(hide yes)
			(effects
				(font
					(size 1.27 1.27)
				)
			)
		)
		(property "Value" "0R2J-2-GP"
			(at 0.064008 -3.993896 0)
			(unlocked yes)
			(layer "F.Fab")
			(hide yes)
			(effects
				(font
					(size 1.016 1.016)
					(thickness 0.1524)
				)
			)
		)
		(property "Device Type" "R402H16"
			(at 0.064008 -5.517896 0)
			(unlocked yes)
			(layer "F.Fab")
			(hide yes)
			(effects
				(font
					(size 1.016 1.016)
					(thickness 0.1524)
				)
			)
		)
		(duplicate_pad_numbers_are_jumpers no)
		(fp_rect
			(start -0.381 0.8382)
			(end 0.381 -0.8382)
			(stroke
				(width 0)
				(type default)
			)
			(fill no)
			(layer "F.CrtYd")
		)
		(fp_rect
			(start -0.381 0.8382)
			(end 0.381 -0.8382)
			(stroke
				(width 0)
				(type default)
			)
			(fill no)
			(layer "F.Fab")
		)
		(pad "1" smd custom
			(at 0 -0.4318)
			(size 0.127 0.127)
			(layers "F.Cu" "F.Mask" "F.Paste")
			(net "EEPROM_CLK")
			(options
				(clearance outline)
				(anchor circle)
			)
			(primitives
				(gr_poly
					(pts
						(arc
							(start -0.2032 -0.2794)
							(mid -0.239121 -0.264521)
							(end -0.254 -0.2286)
						)
						(arc
							(start -0.254 0.2286)
							(mid -0.239121 0.264521)
							(end -0.2032 0.2794)
						)
						(arc
							(start 0.2032 0.2794)
							(mid 0.239121 0.264521)
							(end 0.254 0.2286)
						)
						(arc
							(start 0.254 -0.2286)
							(mid 0.239121 -0.264521)
							(end 0.2032 -0.2794)
						)
					)
					(width 0)
					(fill yes)
				)
			)
		)
		(pad "2" smd custom
			(at 0 0.4318)
			(size 0.127 0.127)
			(layers "F.Cu" "F.Mask" "F.Paste")
			(net "BMC_I2C_CLK")
			(options
				(clearance outline)
				(anchor circle)
			)
			(primitives
				(gr_poly
					(pts
						(arc
							(start -0.2032 -0.2794)
							(mid -0.239121 -0.264521)
							(end -0.254 -0.2286)
						)
						(arc
							(start -0.254 0.2286)
							(mid -0.239121 0.264521)
							(end -0.2032 0.2794)
						)
						(arc
							(start 0.2032 0.2794)
							(mid 0.239121 0.264521)
							(end 0.254 0.2286)
						)
						(arc
							(start 0.254 -0.2286)
							(mid 0.239121 -0.264521)
							(end 0.2032 -0.2794)
						)
					)
					(width 0)
					(fill yes)
				)
			)
		)
	)
	(footprint ""
		(layer "F.Cu")
		(at 50.8 -59.436 90)
		(property "Reference" "PL4"
			(at 0 0 90)
			(layer "F.SilkS")
			(hide yes)
			(effects
				(font
					(size 1.27 1.27)
				)
			)
		)
		(property "Value" "IND-300NH-8-GP"
			(at -4.9403 -2.921 90)
			(unlocked yes)
			(layer "F.Fab")
			(hide yes)
			(effects
				(font
					(size 1.016 1.016)
					(thickness 0.1524)
				)
			)
		)
		(property "Device Type" "L102078-254224H296"
			(at -4.9403 -4.445 90)
			(unlocked yes)
			(layer "F.Fab")
			(hide yes)
			(effects
				(font
					(size 1.016 1.016)
					(thickness 0.1524)
				)
			)
		)
		(duplicate_pad_numbers_are_jumpers no)
		(fp_rect
			(start -4.1529 5.6134)
			(end 4.1529 -5.6134)
			(stroke
				(width 0)
				(type default)
			)
			(fill no)
			(layer "F.CrtYd")
		)
		(fp_rect
			(start -4.1529 5.6134)
			(end 4.1529 -5.6134)
			(stroke
				(width 0)
				(type default)
			)
			(fill no)
			(layer "F.Fab")
		)
		(pad "1" smd rect
			(at 0 -3.893566 90)
			(size 2.4892 3.175)
			(layers "F.Cu" "F.Mask" "F.Paste")
			(net "VR_PVCCP_PWM_OUT")
		)
		(pad "2" smd rect
			(at 0 3.893566 90)
			(size 2.4892 3.175)
			(layers "F.Cu" "F.Mask" "F.Paste")
			(net "PVCCP")
		)
	)
	(footprint ""
		(layer "F.Cu")
		(at 163.957 -60.325 90)
		(property "Reference" "R237"
			(at 0 0 90)
			(layer "F.SilkS")
			(hide yes)
			(effects
				(font
					(size 1.27 1.27)
				)
			)
		)
		(property "Value" "100R2F-L1-GP-U"
			(at 0.064008 -3.993896 90)
			(unlocked yes)
			(layer "F.Fab")
			(hide yes)
			(effects
				(font
					(size 1.016 1.016)
					(thickness 0.1524)
				)
			)
		)
		(property "Device Type" "R402H14"
			(at 0.064008 -5.517896 90)
			(unlocked yes)
			(layer "F.Fab")
			(hide yes)
			(effects
				(font
					(size 1.016 1.016)
					(thickness 0.1524)
				)
			)
		)
		(duplicate_pad_numbers_are_jumpers no)
		(fp_rect
			(start -0.381 0.8382)
			(end 0.381 -0.8382)
			(stroke
				(width 0)
				(type default)
			)
			(fill no)
			(layer "F.CrtYd")
		)
		(fp_rect
			(start -0.381 0.8382)
			(end 0.381 -0.8382)
			(stroke
				(width 0)
				(type default)
			)
			(fill no)
			(layer "F.Fab")
		)
		(pad "1" smd custom
			(at 0 -0.4318 90)
			(size 0.127 0.127)
			(layers "F.Cu" "F.Mask" "F.Paste")
			(net "DDR3_M_A_VREF_CA")
			(options
				(clearance outline)
				(anchor circle)
			)
			(primitives
				(gr_poly
					(pts
						(arc
							(start -0.2032 -0.2794)
							(mid -0.239121 -0.264521)
							(end -0.254 -0.2286)
						)
						(arc
							(start -0.254 0.2286)
							(mid -0.239121 0.264521)
							(end -0.2032 0.2794)
						)
						(arc
							(start 0.2032 0.2794)
							(mid 0.239121 0.264521)
							(end 0.254 0.2286)
						)
						(arc
							(start 0.254 -0.2286)
							(mid 0.239121 -0.264521)
							(end 0.2032 -0.2794)
						)
					)
					(width 0)
					(fill yes)
				)
			)
		)
		(pad "2" smd custom
			(at 0 0.4318 90)
			(size 0.127 0.127)
			(layers "F.Cu" "F.Mask" "F.Paste")
			(net "GND")
			(options
				(clearance outline)
				(anchor circle)
			)
			(primitives
				(gr_poly
					(pts
						(arc
							(start -0.2032 -0.2794)
							(mid -0.239121 -0.264521)
							(end -0.254 -0.2286)
						)
						(arc
							(start -0.254 0.2286)
							(mid -0.239121 0.264521)
							(end -0.2032 0.2794)
						)
						(arc
							(start 0.2032 0.2794)
							(mid 0.239121 0.264521)
							(end 0.254 0.2286)
						)
						(arc
							(start 0.254 -0.2286)
							(mid 0.239121 -0.264521)
							(end 0.2032 -0.2794)
						)
					)
					(width 0)
					(fill yes)
				)
			)
		)
	)
	(footprint ""
		(layer "F.Cu")
		(at 169.7228 -45.847 -90)
		(property "Reference" "R199"
			(at 0 0 270)
			(layer "F.SilkS")
			(hide yes)
			(effects
				(font
					(size 1.27 1.27)
				)
			)
		)
		(property "Value" "0R2J-2-GP"
			(at 1.7907 -1.1176 270)
			(unlocked yes)
			(layer "F.Fab")
			(hide yes)
			(effects
				(font
					(size 1.016 1.016)
					(thickness 0.1524)
				)
			)
		)
		(property "Device Type" "R402H16"
			(at 1.7907 -2.6416 270)
			(unlocked yes)
			(layer "F.Fab")
			(hide yes)
			(effects
				(font
					(size 1.016 1.016)
					(thickness 0.1524)
				)
			)
		)
		(duplicate_pad_numbers_are_jumpers no)
		(fp_rect
			(start -0.381 0.8382)
			(end 0.381 -0.8382)
			(stroke
				(width 0)
				(type default)
			)
			(fill no)
			(layer "F.CrtYd")
		)
		(fp_rect
			(start -0.381 0.8382)
			(end 0.381 -0.8382)
			(stroke
				(width 0)
				(type default)
			)
			(fill no)
			(layer "F.Fab")
		)
		(pad "1" smd custom
			(at 0 -0.4318 270)
			(size 0.127 0.127)
			(layers "F.Cu" "F.Mask" "F.Paste")
			(net "XDP_SOC_CPU_TDI")
			(options
				(clearance outline)
				(anchor circle)
			)
			(primitives
				(gr_poly
					(pts
						(arc
							(start -0.2032 -0.2794)
							(mid -0.239121 -0.264521)
							(end -0.254 -0.2286)
						)
						(arc
							(start -0.254 0.2286)
							(mid -0.239121 0.264521)
							(end -0.2032 0.2794)
						)
						(arc
							(start 0.2032 0.2794)
							(mid 0.239121 0.264521)
							(end 0.254 0.2286)
						)
						(arc
							(start 0.254 -0.2286)
							(mid 0.239121 -0.264521)
							(end 0.2032 -0.2794)
						)
					)
					(width 0)
					(fill yes)
				)
			)
		)
		(pad "2" smd custom
			(at 0 0.4318 270)
			(size 0.127 0.127)
			(layers "F.Cu" "F.Mask" "F.Paste")
			(net "XDP_SOC_CPU_TDI_S")
			(options
				(clearance outline)
				(anchor circle)
			)
			(primitives
				(gr_poly
					(pts
						(arc
							(start -0.2032 -0.2794)
							(mid -0.239121 -0.264521)
							(end -0.254 -0.2286)
						)
						(arc
							(start -0.254 0.2286)
							(mid -0.239121 0.264521)
							(end -0.2032 0.2794)
						)
						(arc
							(start 0.2032 0.2794)
							(mid 0.239121 0.264521)
							(end 0.254 0.2286)
						)
						(arc
							(start 0.254 -0.2286)
							(mid 0.239121 -0.264521)
							(end 0.2032 -0.2794)
						)
					)
					(width 0)
					(fill yes)
				)
			)
		)
	)
)
